# S9S_MB_2U (Grand Teton) — schematic netlist excerpt (pin names and nets, part order shuffled) for the footprints in the layout excerpt that follows; sources: Cadence DE-HDL packaged netlist, KiCad conversion of 03242023_DA0F0TMBIJ0_F0T_Motherboard_J_brd_V01_OCP.brd

R50  Q_RES  499 1% CHIP  pkg 0402LF  page 47 : A = PVNN_TERM_CPU1 ; B = DBP_CPU_MBP1_GTL_N
R4678  Q_RES  1K 1% CHIP  pkg 0402LF  page 260 : A = PWRGD_P5V_ISO_R ; B = PWRGD_P5V_ISO

(kicad_pcb
	(version 20260206)
	(generator "pcbnew")
	(generator_version "10.0")
	(general
		(thickness 1.6)
		(legacy_teardrops no)
	)
	(paper "A4")
	(title_block
		(title "03242023_DA0F0TMBIJ0_F0T_Motherboard_J_brd_V01_OCP.brd")
		(comment 1 "Grand Teton / footprints 5676-5677 of 6105")
	)
	(layers
		(0 "F.Cu" signal "TOP")
		(4 "In1.Cu" signal "GND")
		(6 "In2.Cu" signal "IN1")
		(8 "In3.Cu" signal "GND1")
		(10 "In4.Cu" signal "IN2")
		(12 "In5.Cu" signal "GND2")
		(14 "In6.Cu" signal "IN3")
		(16 "In7.Cu" signal "GND3")
		(18 "In8.Cu" signal "VCC")
		(20 "In9.Cu" signal "VCC1")
		(22 "In10.Cu" signal "GND4")
		(24 "In11.Cu" signal "IN4")
		(26 "In12.Cu" signal "GND5")
		(28 "In13.Cu" signal "IN5")
		(30 "In14.Cu" signal "GND6")
		(32 "In15.Cu" signal "IN6")
		(34 "In16.Cu" signal "GND7")
		(2 "B.Cu" signal "BOTTOM")
		(9 "F.Adhes" user "F.Adhesive")
		(11 "B.Adhes" user "B.Adhesive")
		(13 "F.Paste" user "Package Geometry/Pastemask Top")
		(15 "B.Paste" user "Package Geometry/Pastemask Bottom")
		(5 "F.SilkS" user "Ref Des/Silkscreen Top")
		(7 "B.SilkS" user "Ref Des/Silkscreen Bottom")
		(1 "F.Mask" user "Board Geometry/Soldermask Top")
		(3 "B.Mask" user "Board Geometry/Soldermask Bottom")
		(17 "Dwgs.User" user "User.Drawings")
		(19 "Cmts.User" user "User.Comments")
		(21 "Eco1.User" user "User.Eco1")
		(23 "Eco2.User" user "User.Eco2")
		(25 "Edge.Cuts" user "Board Geometry/Outline")
		(27 "Margin" user)
		(31 "F.CrtYd" user "Package Geometry/Place Bound Top")
		(29 "B.CrtYd" user "Package Geometry/Place Bound Bottom")
		(35 "F.Fab" user "Ref Des/Assembly Top")
		(33 "B.Fab" user "Ref Des/Assembly Bottom")
	)
	(footprint ""
		(layer "B.Cu")
		(at 430.82718 -50.37582 180)
		(property "Reference" "R4678"
			(at 0 0 0)
			(layer "B.SilkS")
			(hide yes)
			(effects
				(font
					(size 1.27 1.27)
				)
				(justify mirror)
			)
		)
		(property "Value" ""
			(at 0 0 0)
			(layer "B.Fab")
			(effects
				(font
					(size 1.27 1.27)
				)
				(justify mirror)
			)
		)
		(duplicate_pad_numbers_are_jumpers no)
		(fp_line
			(start 0.7874 0.4064)
			(end 0.7874 -0.4064)
			(stroke
				(width 0.1524)
				(type default)
			)
			(layer "B.SilkS")
		)
		(fp_line
			(start 0.7874 -0.4064)
			(end -0.7874 -0.4064)
			(stroke
				(width 0.1524)
				(type default)
			)
			(layer "B.SilkS")
		)
		(fp_line
			(start -0.7874 0.4064)
			(end 0.7874 0.4064)
			(stroke
				(width 0.1524)
				(type default)
			)
			(layer "B.SilkS")
		)
		(fp_line
			(start -0.7874 -0.4064)
			(end -0.7874 0.4064)
			(stroke
				(width 0.1524)
				(type default)
			)
			(layer "B.SilkS")
		)
		(fp_line
			(start 0.67945 0.3048)
			(end 0.67945 -0.305054)
			(stroke
				(width 0.1)
				(type default)
			)
			(layer "B.Fab")
		)
		(fp_line
			(start 0.67945 -0.305054)
			(end 0.12065 -0.305054)
			(stroke
				(width 0.1)
				(type default)
			)
			(layer "B.Fab")
		)
		(fp_line
			(start 0.12065 0.3048)
			(end 0.67945 0.3048)
			(stroke
				(width 0.1)
				(type default)
			)
			(layer "B.Fab")
		)
		(fp_line
			(start 0.12065 0.2794)
			(end 0.12065 0.3048)
			(stroke
				(width 0.1)
				(type default)
			)
			(layer "B.Fab")
		)
		(fp_line
			(start 0.12065 -0.2794)
			(end -0.12065 -0.2794)
			(stroke
				(width 0.1)
				(type default)
			)
			(layer "B.Fab")
		)
		(fp_line
			(start 0.12065 -0.305054)
			(end 0.12065 -0.2794)
			(stroke
				(width 0.1)
				(type default)
			)
			(layer "B.Fab")
		)
		(fp_line
			(start -0.120396 0.3048)
			(end -0.120396 0.2794)
			(stroke
				(width 0.1)
				(type default)
			)
			(layer "B.Fab")
		)
		(fp_line
			(start -0.120396 0.2794)
			(end 0.12065 0.2794)
			(stroke
				(width 0.1)
				(type default)
			)
			(layer "B.Fab")
		)
		(fp_line
			(start -0.12065 -0.2794)
			(end -0.12065 -0.3048)
			(stroke
				(width 0.1)
				(type default)
			)
			(layer "B.Fab")
		)
		(fp_line
			(start -0.12065 -0.3048)
			(end -0.67945 -0.3048)
			(stroke
				(width 0.1)
				(type default)
			)
			(layer "B.Fab")
		)
		(fp_line
			(start -0.67945 0.3048)
			(end -0.120396 0.3048)
			(stroke
				(width 0.1)
				(type default)
			)
			(layer "B.Fab")
		)
		(fp_line
			(start -0.67945 -0.3048)
			(end -0.67945 0.3048)
			(stroke
				(width 0.1)
				(type default)
			)
			(layer "B.Fab")
		)
		(pad "1" smd circle
			(at 0.40005 0)
			(size 0 0)
			(layers "B.Cu" "B.Mask" "B.Paste")
			(net "PWRGD_P5V_ISO_R")
		)
		(pad "2" smd circle
			(at -0.40005 0)
			(size 0 0)
			(layers "B.Cu" "B.Mask" "B.Paste")
			(net "PWRGD_P5V_ISO")
		)
	)
	(footprint ""
		(layer "B.Cu")
		(at 72.655684 -183.303926 -90)
		(property "Reference" "R50"
			(at 0 0 90)
			(layer "B.SilkS")
			(hide yes)
			(effects
				(font
					(size 1.27 1.27)
				)
				(justify mirror)
			)
		)
		(property "Value" ""
			(at 0 0 90)
			(layer "B.Fab")
			(effects
				(font
					(size 1.27 1.27)
				)
				(justify mirror)
			)
		)
		(duplicate_pad_numbers_are_jumpers no)
		(fp_line
			(start -0.7874 0.4064)
			(end 0.7874 0.4064)
			(stroke
				(width 0.1524)
				(type default)
			)
			(layer "B.SilkS")
		)
		(fp_line
			(start 0.7874 0.4064)
			(end 0.7874 -0.4064)
			(stroke
				(width 0.1524)
				(type default)
			)
			(layer "B.SilkS")
		)
		(fp_line
			(start -0.7874 -0.4064)
			(end -0.7874 0.4064)
			(stroke
				(width 0.1524)
				(type default)
			)
			(layer "B.SilkS")
		)
		(fp_line
			(start 0.7874 -0.4064)
			(end -0.7874 -0.4064)
			(stroke
				(width 0.1524)
				(type default)
			)
			(layer "B.SilkS")
		)
		(fp_line
			(start -0.67945 0.3048)
			(end -0.120396 0.3048)
			(stroke
				(width 0.1)
				(type default)
			)
			(layer "B.Fab")
		)
		(fp_line
			(start -0.120396 0.3048)
			(end -0.120396 0.2794)
			(stroke
				(width 0.1)
				(type default)
			)
			(layer "B.Fab")
		)
		(fp_line
			(start 0.12065 0.3048)
			(end 0.67945 0.3048)
			(stroke
				(width 0.1)
				(type default)
			)
			(layer "B.Fab")
		)
		(fp_line
			(start 0.67945 0.3048)
			(end 0.67945 -0.305054)
			(stroke
				(width 0.1)
				(type default)
			)
			(layer "B.Fab")
		)
		(fp_line
			(start -0.120396 0.2794)
			(end 0.12065 0.2794)
			(stroke
				(width 0.1)
				(type default)
			)
			(layer "B.Fab")
		)
		(fp_line
			(start 0.12065 0.2794)
			(end 0.12065 0.3048)
			(stroke
				(width 0.1)
				(type default)
			)
			(layer "B.Fab")
		)
		(fp_line
			(start -0.12065 -0.2794)
			(end -0.12065 -0.3048)
			(stroke
				(width 0.1)
				(type default)
			)
			(layer "B.Fab")
		)
		(fp_line
			(start 0.12065 -0.2794)
			(end -0.12065 -0.2794)
			(stroke
				(width 0.1)
				(type default)
			)
			(layer "B.Fab")
		)
		(fp_line
			(start -0.67945 -0.3048)
			(end -0.67945 0.3048)
			(stroke
				(width 0.1)
				(type default)
			)
			(layer "B.Fab")
		)
		(fp_line
			(start -0.12065 -0.3048)
			(end -0.67945 -0.3048)
			(stroke
				(width 0.1)
				(type default)
			)
			(layer "B.Fab")
		)
		(fp_line
			(start 0.12065 -0.305054)
			(end 0.12065 -0.2794)
			(stroke
				(width 0.1)
				(type default)
			)
			(layer "B.Fab")
		)
		(fp_line
			(start 0.67945 -0.305054)
			(end 0.12065 -0.305054)
			(stroke
				(width 0.1)
				(type default)
			)
			(layer "B.Fab")
		)
		(pad "1" smd circle
			(at 0.40005 0 90)
			(size 0 0)
			(layers "B.Cu" "B.Mask" "B.Paste")
			(net "PVNN_TERM_CPU1")
		)
		(pad "2" smd circle
			(at -0.40005 0 90)
			(size 0 0)
			(layers "B.Cu" "B.Mask" "B.Paste")
			(net "DBP_CPU_MBP1_GTL_N")
		)
	)
)
